# T6G (Grand Teton) — schematic netlist excerpt (pin names and nets, part order shuffled) for the footprints in the layout excerpt that follows; sources: Cadence DE-HDL packaged netlist, KiCad conversion of 04192023_DAF0TMB3IC0_F0TG_MB_C_brd_V02_OCP.brd

C1529  Q_CAP_DIFFBUS  DIFF BUS_0.22UF 6.3V 20% X6S  pkg C0201  page 67 : \1\ = P5E_CPU1_P3_TX_C_DP<9> ; \2\ = P5E_CPU1_P3_TX_DP<9>
C2555  Q_CAP  22UF 4V 20% X6S  pkg C0402  page 70 : A = PVDDCR_SOC_P0 ; B = GND
R1166  Q_RES  0 5% CHIP  pkg 0402LF  page 142 : A = P12V_OCP_V3_2_PLD_R_PWRGD ; B = P12V_OCP_V3_2_PLD_PWRGD

(kicad_pcb
	(version 20260206)
	(generator "pcbnew")
	(generator_version "10.0")
	(general
		(thickness 1.6)
		(legacy_teardrops no)
	)
	(paper "A4")
	(title_block
		(title "04192023_DAF0TMB3IC0_F0TG_MB_C_brd_V02_OCP.brd")
		(comment 1 "Grand Teton / footprints 678-680 of 8354")
	)
	(layers
		(0 "F.Cu" signal "TOP")
		(4 "In1.Cu" signal "GND")
		(6 "In2.Cu" signal "IN1")
		(8 "In3.Cu" signal "GND1")
		(10 "In4.Cu" signal "IN2")
		(12 "In5.Cu" signal "GND2")
		(14 "In6.Cu" signal "IN3")
		(16 "In7.Cu" signal "GND3")
		(18 "In8.Cu" signal "VCC")
		(20 "In9.Cu" signal "VCC1")
		(22 "In10.Cu" signal "GND4")
		(24 "In11.Cu" signal "IN4")
		(26 "In12.Cu" signal "GND5")
		(28 "In13.Cu" signal "IN5")
		(30 "In14.Cu" signal "GND6")
		(32 "In15.Cu" signal "IN6")
		(34 "In16.Cu" signal "GND7")
		(2 "B.Cu" signal "BOTTOM")
		(9 "F.Adhes" user "F.Adhesive")
		(11 "B.Adhes" user "B.Adhesive")
		(13 "F.Paste" user "Package Geometry/Pastemask Top")
		(15 "B.Paste" user "Package Geometry/Pastemask Bottom")
		(5 "F.SilkS" user "Ref Des/Silkscreen Top")
		(7 "B.SilkS" user "Ref Des/Silkscreen Bottom")
		(1 "F.Mask" user "Board Geometry/Soldermask Top")
		(3 "B.Mask" user "Board Geometry/Soldermask Bottom")
		(17 "Dwgs.User" user "User.Drawings")
		(19 "Cmts.User" user "User.Comments")
		(21 "Eco1.User" user "User.Eco1")
		(23 "Eco2.User" user "User.Eco2")
		(25 "Edge.Cuts" user "Board Geometry/Outline")
		(27 "Margin" user)
		(31 "F.CrtYd" user "Package Geometry/Place Bound Top")
		(29 "B.CrtYd" user "Package Geometry/Place Bound Bottom")
		(35 "F.Fab" user "Ref Des/Assembly Top")
		(33 "B.Fab" user "Ref Des/Assembly Bottom")
	)
	(footprint ""
		(layer "F.Cu")
		(at 365.835692 -261.255002 180)
		(property "Reference" "C2555"
			(at 0 0 180)
			(layer "F.SilkS")
			(hide yes)
			(effects
				(font
					(size 1.27 1.27)
				)
			)
		)
		(property "Value" ""
			(at 0 0 180)
			(layer "F.Fab")
			(effects
				(font
					(size 1.27 1.27)
				)
			)
		)
		(duplicate_pad_numbers_are_jumpers no)
		(fp_line
			(start 0.7874 0.4064)
			(end -0.7874 0.4064)
			(stroke
				(width 0.1524)
				(type default)
			)
			(layer "F.SilkS")
		)
		(fp_line
			(start 0.7874 -0.4064)
			(end 0.7874 0.4064)
			(stroke
				(width 0.1524)
				(type default)
			)
			(layer "F.SilkS")
		)
		(fp_line
			(start -0.7874 0.4064)
			(end -0.7874 -0.4064)
			(stroke
				(width 0.1524)
				(type default)
			)
			(layer "F.SilkS")
		)
		(fp_line
			(start -0.7874 -0.4064)
			(end 0.7874 -0.4064)
			(stroke
				(width 0.1524)
				(type default)
			)
			(layer "F.SilkS")
		)
		(fp_line
			(start 0.67945 0.3048)
			(end 0.120396 0.3048)
			(stroke
				(width 0.1)
				(type default)
			)
			(layer "F.Fab")
		)
		(fp_line
			(start 0.67945 -0.3048)
			(end 0.67945 0.3048)
			(stroke
				(width 0.1)
				(type default)
			)
			(layer "F.Fab")
		)
		(fp_line
			(start 0.12065 -0.2794)
			(end 0.12065 -0.3048)
			(stroke
				(width 0.1)
				(type default)
			)
			(layer "F.Fab")
		)
		(fp_line
			(start 0.12065 -0.3048)
			(end 0.67945 -0.3048)
			(stroke
				(width 0.1)
				(type default)
			)
			(layer "F.Fab")
		)
		(fp_line
			(start 0.120396 0.3048)
			(end 0.120396 0.2794)
			(stroke
				(width 0.1)
				(type default)
			)
			(layer "F.Fab")
		)
		(fp_line
			(start 0.120396 0.2794)
			(end -0.12065 0.2794)
			(stroke
				(width 0.1)
				(type default)
			)
			(layer "F.Fab")
		)
		(fp_line
			(start -0.12065 0.3048)
			(end -0.67945 0.3048)
			(stroke
				(width 0.1)
				(type default)
			)
			(layer "F.Fab")
		)
		(fp_line
			(start -0.12065 0.2794)
			(end -0.12065 0.3048)
			(stroke
				(width 0.1)
				(type default)
			)
			(layer "F.Fab")
		)
		(fp_line
			(start -0.12065 -0.2794)
			(end 0.12065 -0.2794)
			(stroke
				(width 0.1)
				(type default)
			)
			(layer "F.Fab")
		)
		(fp_line
			(start -0.12065 -0.305054)
			(end -0.12065 -0.2794)
			(stroke
				(width 0.1)
				(type default)
			)
			(layer "F.Fab")
		)
		(fp_line
			(start -0.67945 0.3048)
			(end -0.67945 -0.305054)
			(stroke
				(width 0.1)
				(type default)
			)
			(layer "F.Fab")
		)
		(fp_line
			(start -0.67945 -0.305054)
			(end -0.12065 -0.305054)
			(stroke
				(width 0.1)
				(type default)
			)
			(layer "F.Fab")
		)
		(pad "1" smd circle
			(at -0.40005 0 180)
			(size 0 0)
			(layers "F.Cu" "F.Mask" "F.Paste")
			(net "PVDDCR_SOC_P0")
		)
		(pad "2" smd circle
			(at 0.40005 0 180)
			(size 0 0)
			(layers "F.Cu" "F.Mask" "F.Paste")
			(net "GND")
		)
	)
	(footprint ""
		(layer "F.Cu")
		(at 100.457 -77.216)
		(property "Reference" "R1166"
			(at 0 0 0)
			(layer "F.SilkS")
			(hide yes)
			(effects
				(font
					(size 1.27 1.27)
				)
			)
		)
		(property "Value" ""
			(at 0 0 0)
			(layer "F.Fab")
			(effects
				(font
					(size 1.27 1.27)
				)
			)
		)
		(duplicate_pad_numbers_are_jumpers no)
		(fp_line
			(start -0.7874 -0.4064)
			(end 0.7874 -0.4064)
			(stroke
				(width 0.1524)
				(type default)
			)
			(layer "F.SilkS")
		)
		(fp_line
			(start -0.7874 0.4064)
			(end -0.7874 -0.4064)
			(stroke
				(width 0.1524)
				(type default)
			)
			(layer "F.SilkS")
		)
		(fp_line
			(start 0.7874 -0.4064)
			(end 0.7874 0.4064)
			(stroke
				(width 0.1524)
				(type default)
			)
			(layer "F.SilkS")
		)
		(fp_line
			(start 0.7874 0.4064)
			(end -0.7874 0.4064)
			(stroke
				(width 0.1524)
				(type default)
			)
			(layer "F.SilkS")
		)
		(fp_line
			(start -0.67945 -0.305054)
			(end -0.12065 -0.305054)
			(stroke
				(width 0.1)
				(type default)
			)
			(layer "F.Fab")
		)
		(fp_line
			(start -0.67945 0.3048)
			(end -0.67945 -0.305054)
			(stroke
				(width 0.1)
				(type default)
			)
			(layer "F.Fab")
		)
		(fp_line
			(start -0.12065 -0.305054)
			(end -0.12065 -0.2794)
			(stroke
				(width 0.1)
				(type default)
			)
			(layer "F.Fab")
		)
		(fp_line
			(start -0.12065 -0.2794)
			(end 0.12065 -0.2794)
			(stroke
				(width 0.1)
				(type default)
			)
			(layer "F.Fab")
		)
		(fp_line
			(start -0.12065 0.2794)
			(end -0.12065 0.3048)
			(stroke
				(width 0.1)
				(type default)
			)
			(layer "F.Fab")
		)
		(fp_line
			(start -0.12065 0.3048)
			(end -0.67945 0.3048)
			(stroke
				(width 0.1)
				(type default)
			)
			(layer "F.Fab")
		)
		(fp_line
			(start 0.120396 0.2794)
			(end -0.12065 0.2794)
			(stroke
				(width 0.1)
				(type default)
			)
			(layer "F.Fab")
		)
		(fp_line
			(start 0.120396 0.3048)
			(end 0.120396 0.2794)
			(stroke
				(width 0.1)
				(type default)
			)
			(layer "F.Fab")
		)
		(fp_line
			(start 0.12065 -0.3048)
			(end 0.67945 -0.3048)
			(stroke
				(width 0.1)
				(type default)
			)
			(layer "F.Fab")
		)
		(fp_line
			(start 0.12065 -0.2794)
			(end 0.12065 -0.3048)
			(stroke
				(width 0.1)
				(type default)
			)
			(layer "F.Fab")
		)
		(fp_line
			(start 0.67945 -0.3048)
			(end 0.67945 0.3048)
			(stroke
				(width 0.1)
				(type default)
			)
			(layer "F.Fab")
		)
		(fp_line
			(start 0.67945 0.3048)
			(end 0.120396 0.3048)
			(stroke
				(width 0.1)
				(type default)
			)
			(layer "F.Fab")
		)
		(pad "1" smd circle
			(at -0.40005 0)
			(size 0 0)
			(layers "F.Cu" "F.Mask" "F.Paste")
			(net "P12V_OCP_V3_2_PLD_R_PWRGD")
		)
		(pad "2" smd circle
			(at 0.40005 0)
			(size 0 0)
			(layers "F.Cu" "F.Mask" "F.Paste")
			(net "P12V_OCP_V3_2_PLD_PWRGD")
		)
	)
	(footprint ""
		(layer "F.Cu")
		(at 125.405896 -370.57203 -90)
		(property "Reference" "C1529"
			(at 0 0 270)
			(layer "F.SilkS")
			(hide yes)
			(effects
				(font
					(size 1.27 1.27)
				)
			)
		)
		(property "Value" ""
			(at 0 0 270)
			(layer "F.Fab")
			(effects
				(font
					(size 1.27 1.27)
				)
			)
		)
		(duplicate_pad_numbers_are_jumpers no)
		(fp_line
			(start -0.299974 0.150114)
			(end -0.299974 -0.150114)
			(stroke
				(width 0.1)
				(type default)
			)
			(layer "F.Fab")
		)
		(fp_line
			(start 0.299974 0.150114)
			(end -0.299974 0.150114)
			(stroke
				(width 0.1)
				(type default)
			)
			(layer "F.Fab")
		)
		(fp_line
			(start -0.299974 -0.150114)
			(end 0.299974 -0.150114)
			(stroke
				(width 0.1)
				(type default)
			)
			(layer "F.Fab")
		)
		(fp_line
			(start 0.299974 -0.150114)
			(end 0.299974 0.150114)
			(stroke
				(width 0.1)
				(type default)
			)
			(layer "F.Fab")
		)
		(pad "1" smd rect
			(at -0.2667 0 270)
			(size 0.3048 0.381)
			(layers "F.Cu" "F.Mask" "F.Paste")
			(net "P5E_CPU1_P3_TX_C_DP<9>")
		)
		(pad "2" smd rect
			(at 0.2667 0 270)
			(size 0.3048 0.381)
			(layers "F.Cu" "F.Mask" "F.Paste")
			(net "P5E_CPU1_P3_TX_DP<9>")
		)
	)
)
